(kicad_pcb
	(version 20260206)
	(generator "pcbnew")
	(generator_version "10.0")
	(general
		(thickness 1.6)
		(legacy_teardrops no)
	)
	(paper "A4")
	(title_block
		(title "Wiwynn_Tioga_Pass_MB.brd")
		(comment 1 "Tioga Pass / footprints 2317-2323 of 4770")
	)
	(layers
		(0 "F.Cu" signal "TOP")
		(4 "In1.Cu" signal "L2GND")
		(6 "In2.Cu" signal "L3")
		(8 "In3.Cu" signal "L4GND")
		(10 "In4.Cu" signal "L5")
		(12 "In5.Cu" signal "L6GND")
		(14 "In6.Cu" signal "L7VCC")
		(16 "In7.Cu" signal "L8VCC")
		(18 "In8.Cu" signal "L9GND")
		(20 "In9.Cu" signal "L10")
		(22 "In10.Cu" signal "L11GND")
		(24 "In11.Cu" signal "L12")
		(26 "In12.Cu" signal "L13GND")
		(2 "B.Cu" signal "BOTTOM")
		(9 "F.Adhes" user "F.Adhesive")
		(11 "B.Adhes" user "B.Adhesive")
		(13 "F.Paste" user "Package Geometry/Pastemask Top")
		(15 "B.Paste" user "Package Geometry/Pastemask Bottom")
		(5 "F.SilkS" user "Ref Des/Silkscreen Top")
		(7 "B.SilkS" user "Ref Des/Silkscreen Bottom")
		(1 "F.Mask" user "Board Geometry/Soldermask Top")
		(3 "B.Mask" user "Board Geometry/Soldermask Bottom")
		(17 "Dwgs.User" user "User.Drawings")
		(19 "Cmts.User" user "User.Comments")
		(21 "Eco1.User" user "User.Eco1")
		(23 "Eco2.User" user "User.Eco2")
		(25 "Edge.Cuts" user "Board Geometry/Outline")
		(27 "Margin" user)
		(31 "F.CrtYd" user "Package Geometry/Place Bound Top")
		(29 "B.CrtYd" user "Package Geometry/Place Bound Bottom")
		(35 "F.Fab" user "Ref Des/Assembly Top")
		(33 "B.Fab" user "Ref Des/Assembly Bottom")
	)
	(footprint ""
		(layer "F.Cu")
		(at 156.539692 -164.904674 -90)
		(property "Reference" "T1D13"
			(at 0 0 270)
			(layer "F.SilkS")
			(hide yes)
			(effects
				(font
					(size 1.27 1.27)
				)
			)
		)
		(property "Value" "*"
			(at -3.4036 -4.46405 270)
			(unlocked yes)
			(layer "F.Fab")
			(hide yes)
			(effects
				(font
					(size 0.889 0.889)
					(thickness 0.1524)
				)
			)
		)
		(property "Device Type" "TEST-PAD-12P-1-GP-U_DISCRET-GBA"
			(at -3.4036 -5.98805 270)
			(unlocked yes)
			(layer "F.Fab")
			(hide yes)
			(effects
				(font
					(size 0.889 0.889)
					(thickness 0.1524)
				)
			)
		)
		(duplicate_pad_numbers_are_jumpers no)
		(fp_line
			(start -2.3876 3.4798)
			(end -2.3876 -4.826)
			(stroke
				(width 0.1524)
				(type default)
			)
			(layer "F.SilkS")
		)
		(fp_line
			(start 2.3622 3.4798)
			(end -2.3876 3.4798)
			(stroke
				(width 0.1524)
				(type default)
			)
			(layer "F.SilkS")
		)
		(fp_line
			(start -2.3876 -4.826)
			(end 2.3622 -4.826)
			(stroke
				(width 0.1524)
				(type default)
			)
			(layer "F.SilkS")
		)
		(fp_line
			(start 2.3622 -4.826)
			(end 2.3622 3.4798)
			(stroke
				(width 0.1524)
				(type default)
			)
			(layer "F.SilkS")
		)
		(fp_rect
			(start -2.6416 3.7338)
			(end 2.6162 -5.08)
			(stroke
				(width 0)
				(type default)
			)
			(fill no)
			(layer "F.CrtYd")
		)
		(fp_rect
			(start -2.6416 3.7338)
			(end 2.6162 -5.08)
			(stroke
				(width 0)
				(type default)
			)
			(fill no)
			(layer "F.Fab")
		)
		(pad "1" smd circle
			(at 0.496824 -1.301496 270)
			(size 0.6604 0.6604)
			(layers "F.Cu" "F.Mask" "F.Paste")
			(net "L1_85OHM_10INCH_DP")
		)
		(pad "2" smd circle
			(at -0.503936 -1.301496 270)
			(size 0.6604 0.6604)
			(layers "F.Cu" "F.Mask" "F.Paste")
			(net "L1_85OHM_10INCH_DN")
		)
		(pad "3" smd custom
			(at -0.00889 0.370078 270)
			(size 0.74295 0.74295)
			(layers "F.Cu" "F.Mask" "F.Paste")
			(net "GND")
			(options
				(clearance outline)
				(anchor circle)
			)
			(primitives
				(gr_poly
					(pts
						(xy -2.1209 1.4859) (xy 2.1209 1.4859) (xy 2.1209 -1.4859) (xy 1.08585 -1.4859) (xy 1.08585 -0.4699)
						(xy -1.08585 -0.4699) (xy -1.08585 -1.4859) (xy -2.1209 -1.4859)
					)
					(width 0)
					(fill yes)
				)
			)
		)
		(pad "4" thru_hole circle
			(at 1.266444 -3.851656 270)
			(size 1.4478 1.4478)
			(drill 1.0414)
			(layers "*.Cu" "*.Mask")
			(remove_unused_layers no)
			(net "GND")
			(clearance 0.1524)
			(thermal_gap 0.1524)
		)
		(pad "5" thru_hole circle
			(at -1.273556 -3.851656 270)
			(size 1.4478 1.4478)
			(drill 1.0414)
			(layers "*.Cu" "*.Mask")
			(remove_unused_layers no)
			(net "GND")
			(clearance 0.1524)
			(thermal_gap 0.1524)
		)
		(pad "6" thru_hole circle
			(at 1.266444 2.498344 270)
			(size 1.4478 1.4478)
			(drill 1.0414)
			(layers "*.Cu" "*.Mask")
			(remove_unused_layers no)
			(net "GND")
			(clearance 0.1524)
			(thermal_gap 0.1524)
		)
		(pad "7" thru_hole circle
			(at -1.273556 2.498344 270)
			(size 1.4478 1.4478)
			(drill 1.0414)
			(layers "*.Cu" "*.Mask")
			(remove_unused_layers no)
			(net "GND")
			(clearance 0.1524)
			(thermal_gap 0.1524)
		)
		(pad "8" thru_hole circle
			(at 1.27 -0.4572 270)
			(size 0.7112 0.7112)
			(drill 0.4064)
			(layers "*.Cu" "*.Mask")
			(remove_unused_layers no)
			(net "GND")
			(clearance 0.1016)
			(thermal_gap 0.1016)
		)
		(pad "9" thru_hole circle
			(at 1.27 0.762 270)
			(size 0.7112 0.7112)
			(drill 0.4064)
			(layers "*.Cu" "*.Mask")
			(remove_unused_layers no)
			(net "GND")
			(clearance 0.1016)
			(thermal_gap 0.1016)
		)
		(pad "10" thru_hole circle
			(at -0.0254 0.762 270)
			(size 0.7112 0.7112)
			(drill 0.4064)
			(layers "*.Cu" "*.Mask")
			(remove_unused_layers no)
			(net "GND")
			(clearance 0.1016)
			(thermal_gap 0.1016)
		)
		(pad "11" thru_hole circle
			(at -1.27 0.762 270)
			(size 0.7112 0.7112)
			(drill 0.4064)
			(layers "*.Cu" "*.Mask")
			(remove_unused_layers no)
			(net "GND")
			(clearance 0.1016)
			(thermal_gap 0.1016)
		)
		(pad "12" thru_hole circle
			(at -1.27 -0.4572 270)
			(size 0.7112 0.7112)
			(drill 0.4064)
			(layers "*.Cu" "*.Mask")
			(remove_unused_layers no)
			(net "GND")
			(clearance 0.1016)
			(thermal_gap 0.1016)
		)
	)
	(footprint ""
		(layer "F.Cu")
		(at 435.727094 -150.043642)
		(property "Reference" "R25W170"
			(at -0.8382 -0.677926 0)
			(unlocked yes)
			(layer "F.SilkS")
			(effects
				(font
					(size 0.4064 0.254)
					(thickness 0.1524)
				)
				(justify left)
			)
		)
		(property "Value" ""
			(at 0 0 0)
			(layer "F.Fab")
			(effects
				(font
					(size 1.27 1.27)
				)
			)
		)
		(duplicate_pad_numbers_are_jumpers no)
		(fp_poly
			(pts
				(xy -0.2794 -0.1016) (xy 0.2794 -0.1016) (xy 0.2794 0.9906) (xy -0.2794 0.9906)
			)
			(stroke
				(width 0)
				(type default)
			)
			(fill no)
			(layer "F.CrtYd")
		)
		(fp_line
			(start -0.2794 -0.1016)
			(end -0.2794 0.9906)
			(stroke
				(width 0.1)
				(type default)
			)
			(layer "F.Fab")
		)
		(fp_line
			(start -0.2794 0.9906)
			(end 0.2794 0.9906)
			(stroke
				(width 0.1)
				(type default)
			)
			(layer "F.Fab")
		)
		(fp_line
			(start 0.2794 -0.1016)
			(end -0.2794 -0.1016)
			(stroke
				(width 0.1)
				(type default)
			)
			(layer "F.Fab")
		)
		(fp_line
			(start 0.2794 0.9906)
			(end 0.2794 -0.1016)
			(stroke
				(width 0.1)
				(type default)
			)
			(layer "F.Fab")
		)
		(pad "1" smd rect
			(at 0 0)
			(size 0.508 0.508)
			(layers "F.Cu" "F.Mask" "F.Paste")
			(net "JTAG_BMC_TRST_BUF_N")
		)
		(pad "2" smd rect
			(at 0 0.889)
			(size 0.508 0.508)
			(layers "F.Cu" "F.Mask" "F.Paste")
			(net "GND")
		)
		(zone
			(layer "F.Cu")
			(hatch none 0.5)
			(connect_pads
				(clearance 0)
			)
			(min_thickness 0.25)
			(keepout
				(tracks allowed)
				(vias not_allowed)
				(pads allowed)
				(copperpour not_allowed)
				(footprints allowed)
			)
			(placement
				(enabled no)
				(sheetname "")
			)
			(fill
				(thermal_gap 0.5)
				(thermal_bridge_width 0.5)
				(island_removal_mode 0)
			)
			(polygon
				(pts
					(xy 435.473094 -149.789642) (xy 435.981094 -149.789642) (xy 435.981094 -149.408642) (xy 435.473094 -149.408642)
				)
			)
		)
		(zone
			(layer "F.Cu")
			(hatch none 0.5)
			(connect_pads
				(clearance 0)
			)
			(min_thickness 0.25)
			(keepout
				(tracks not_allowed)
				(vias allowed)
				(pads allowed)
				(copperpour not_allowed)
				(footprints allowed)
			)
			(placement
				(enabled no)
				(sheetname "")
			)
			(fill
				(thermal_gap 0.5)
				(thermal_bridge_width 0.5)
				(island_removal_mode 0)
			)
			(polygon
				(pts
					(xy 435.473094 -149.408642) (xy 435.981094 -149.408642) (xy 435.981094 -149.789642) (xy 435.473094 -149.789642)
				)
			)
		)
	)
	(footprint ""
		(layer "F.Cu")
		(at 175.387 -77.597 90)
		(property "Reference" "R4D25"
			(at 0 0 90)
			(layer "F.SilkS")
			(hide yes)
			(effects
				(font
					(size 1.27 1.27)
				)
			)
		)
		(property "Value" ""
			(at 0 0 90)
			(layer "F.Fab")
			(effects
				(font
					(size 1.27 1.27)
				)
			)
		)
		(duplicate_pad_numbers_are_jumpers no)
		(fp_poly
			(pts
				(xy -0.2794 -0.1016) (xy 0.2794 -0.1016) (xy 0.2794 0.9906) (xy -0.2794 0.9906)
			)
			(stroke
				(width 0)
				(type default)
			)
			(fill no)
			(layer "F.CrtYd")
		)
		(fp_line
			(start 0.2794 -0.1016)
			(end -0.2794 -0.1016)
			(stroke
				(width 0.1)
				(type default)
			)
			(layer "F.Fab")
		)
		(fp_line
			(start -0.2794 -0.1016)
			(end -0.2794 0.9906)
			(stroke
				(width 0.1)
				(type default)
			)
			(layer "F.Fab")
		)
		(fp_line
			(start 0.2794 0.9906)
			(end 0.2794 -0.1016)
			(stroke
				(width 0.1)
				(type default)
			)
			(layer "F.Fab")
		)
		(fp_line
			(start -0.2794 0.9906)
			(end 0.2794 0.9906)
			(stroke
				(width 0.1)
				(type default)
			)
			(layer "F.Fab")
		)
		(pad "1" smd rect
			(at 0 0 90)
			(size 0.508 0.508)
			(layers "F.Cu" "F.Mask" "F.Paste")
			(net "CLK_100M_CPU0_BCLK0_R_DN")
		)
		(pad "2" smd rect
			(at 0 0.889 90)
			(size 0.508 0.508)
			(layers "F.Cu" "F.Mask" "F.Paste")
			(net "CLK_100M_CPU0_BCLK0_DN")
		)
		(zone
			(layer "F.Cu")
			(hatch none 0.5)
			(connect_pads
				(clearance 0)
			)
			(min_thickness 0.25)
			(keepout
				(tracks allowed)
				(vias not_allowed)
				(pads allowed)
				(copperpour not_allowed)
				(footprints allowed)
			)
			(placement
				(enabled no)
				(sheetname "")
			)
			(fill
				(thermal_gap 0.5)
				(thermal_bridge_width 0.5)
				(island_removal_mode 0)
			)
			(polygon
				(pts
					(xy 175.641 -77.343) (xy 175.641 -77.851) (xy 176.022 -77.851) (xy 176.022 -77.343)
				)
			)
		)
		(zone
			(layer "F.Cu")
			(hatch none 0.5)
			(connect_pads
				(clearance 0)
			)
			(min_thickness 0.25)
			(keepout
				(tracks not_allowed)
				(vias allowed)
				(pads allowed)
				(copperpour not_allowed)
				(footprints allowed)
			)
			(placement
				(enabled no)
				(sheetname "")
			)
			(fill
				(thermal_gap 0.5)
				(thermal_bridge_width 0.5)
				(island_removal_mode 0)
			)
			(polygon
				(pts
					(xy 176.022 -77.343) (xy 176.022 -77.851) (xy 175.641 -77.851) (xy 175.641 -77.343)
				)
			)
		)
	)
	(footprint ""
		(layer "F.Cu")
		(at 349.735648 -21.279612)
		(property "Reference" "R12W1"
			(at 0 0 0)
			(layer "F.SilkS")
			(hide yes)
			(effects
				(font
					(size 1.27 1.27)
				)
			)
		)
		(property "Value" "*"
			(at 0 -8.9535 0)
			(unlocked yes)
			(layer "F.Fab")
			(hide yes)
			(effects
				(font
					(size 1.27 1.016)
					(thickness 0.1524)
				)
			)
		)
		(property "Device Type" "665KR5B-1-GP_SMD-RG3-665KR5B-1A"
			(at 0 -10.6299 0)
			(unlocked yes)
			(layer "F.Fab")
			(hide yes)
			(effects
				(font
					(size 1.27 1.016)
					(thickness 0.1524)
				)
			)
		)
		(duplicate_pad_numbers_are_jumpers no)
		(fp_line
			(start -0.889 -1.7018)
			(end -0.889 0.2794)
			(stroke
				(width 0.1524)
				(type default)
			)
			(layer "F.SilkS")
		)
		(fp_line
			(start -0.889 0.0762)
			(end -0.889 1.7018)
			(stroke
				(width 0.1524)
				(type default)
			)
			(layer "F.SilkS")
		)
		(fp_line
			(start -0.889 1.7018)
			(end 0.889 1.7018)
			(stroke
				(width 0.1524)
				(type default)
			)
			(layer "F.SilkS")
		)
		(fp_line
			(start 0.889 -1.7018)
			(end -0.889 -1.7018)
			(stroke
				(width 0.1524)
				(type default)
			)
			(layer "F.SilkS")
		)
		(fp_line
			(start 0.889 -1.7018)
			(end 0.889 -0.381)
			(stroke
				(width 0.1524)
				(type default)
			)
			(layer "F.SilkS")
		)
		(fp_line
			(start 0.889 1.7018)
			(end 0.889 -0.508)
			(stroke
				(width 0.1524)
				(type default)
			)
			(layer "F.SilkS")
		)
		(fp_poly
			(pts
				(xy 0.9652 -1.778) (xy 0.9652 1.778) (xy -0.9652 1.778) (xy -0.9652 -1.778)
			)
			(stroke
				(width 0)
				(type default)
			)
			(fill no)
			(layer "F.CrtYd")
		)
		(fp_rect
			(start -0.9652 1.778)
			(end 0.9652 -1.778)
			(stroke
				(width 0)
				(type default)
			)
			(fill no)
			(layer "F.Fab")
		)
		(pad "1" smd rect
			(at 0 -0.9652)
			(size 1.397 1.143)
			(layers "F.Cu" "F.Mask" "F.Paste")
			(net "P12V_STBY")
		)
		(pad "2" smd rect
			(at 0 0.9652)
			(size 1.397 1.143)
			(layers "F.Cu" "F.Mask" "F.Paste")
			(net "VR_PVDDQ_ABC_AIINSEN")
		)
	)
	(footprint ""
		(layer "F.Cu")
		(at 4.31546 -132.49402 180)
		(property "Reference" "C1B2"
			(at -0.8382 -0.67818 180)
			(unlocked yes)
			(layer "F.SilkS")
			(effects
				(font
					(size 0.4064 0.254)
					(thickness 0.1524)
				)
				(justify left)
			)
		)
		(property "Value" ""
			(at 0 0 180)
			(layer "F.Fab")
			(effects
				(font
					(size 1.27 1.27)
				)
			)
		)
		(duplicate_pad_numbers_are_jumpers no)
		(fp_poly
			(pts
				(xy 0.3048 -0.1016) (xy 0.3048 0.9906) (xy -0.3048 0.9906) (xy -0.3048 -0.1016)
			)
			(stroke
				(width 0)
				(type default)
			)
			(fill no)
			(layer "F.CrtYd")
		)
		(fp_line
			(start 0.3048 0.9906)
			(end 0.3048 -0.1016)
			(stroke
				(width 0.1)
				(type default)
			)
			(layer "F.Fab")
		)
		(fp_line
			(start 0.3048 -0.1016)
			(end -0.3048 -0.1016)
			(stroke
				(width 0.1)
				(type default)
			)
			(layer "F.Fab")
		)
		(fp_line
			(start -0.3048 0.9906)
			(end 0.3048 0.9906)
			(stroke
				(width 0.1)
				(type default)
			)
			(layer "F.Fab")
		)
		(fp_line
			(start -0.3048 -0.1016)
			(end -0.3048 0.9906)
			(stroke
				(width 0.1)
				(type default)
			)
			(layer "F.Fab")
		)
		(pad "1" smd rect
			(at 0 0 180)
			(size 0.508 0.508)
			(layers "F.Cu" "F.Mask" "F.Paste")
			(net "VR_PVDDQ_KLM_VD12")
		)
		(pad "2" smd rect
			(at 0 0.889 180)
			(size 0.508 0.508)
			(layers "F.Cu" "F.Mask" "F.Paste")
			(net "GND")
		)
		(zone
			(layer "F.Cu")
			(hatch none 0.5)
			(connect_pads
				(clearance 0)
			)
			(min_thickness 0.25)
			(keepout
				(tracks not_allowed)
				(vias allowed)
				(pads allowed)
				(copperpour not_allowed)
				(footprints allowed)
			)
			(placement
				(enabled no)
				(sheetname "")
			)
			(fill
				(thermal_gap 0.5)
				(thermal_bridge_width 0.5)
				(island_removal_mode 0)
			)
			(polygon
				(pts
					(xy 4.56946 -133.12902) (xy 4.06146 -133.12902) (xy 4.06146 -132.74802) (xy 4.56946 -132.74802)
				)
			)
		)
		(zone
			(layer "F.Cu")
			(hatch none 0.5)
			(connect_pads
				(clearance 0)
			)
			(min_thickness 0.25)
			(keepout
				(tracks allowed)
				(vias not_allowed)
				(pads allowed)
				(copperpour not_allowed)
				(footprints allowed)
			)
			(placement
				(enabled no)
				(sheetname "")
			)
			(fill
				(thermal_gap 0.5)
				(thermal_bridge_width 0.5)
				(island_removal_mode 0)
			)
			(polygon
				(pts
					(xy 4.56946 -132.74802) (xy 4.06146 -132.74802) (xy 4.06146 -133.12902) (xy 4.56946 -133.12902)
				)
			)
		)
	)
	(footprint ""
		(layer "F.Cu")
		(at 20.5232 -97.310956 180)
		(property "Reference" "C1C11"
			(at 0 0 180)
			(layer "F.SilkS")
			(hide yes)
			(effects
				(font
					(size 1.27 1.27)
				)
			)
		)
		(property "Value" ""
			(at 0 0 180)
			(layer "F.Fab")
			(effects
				(font
					(size 1.27 1.27)
				)
			)
		)
		(duplicate_pad_numbers_are_jumpers no)
		(fp_rect
			(start 0.3048 -0.1016)
			(end -0.3048 0.9906)
			(stroke
				(width 0)
				(type default)
			)
			(fill no)
			(layer "F.CrtYd")
		)
		(fp_line
			(start 0.3048 0.9906)
			(end 0.3048 -0.1016)
			(stroke
				(width 0.1)
				(type default)
			)
			(layer "F.Fab")
		)
		(fp_line
			(start 0.3048 -0.1016)
			(end -0.3048 -0.1016)
			(stroke
				(width 0.1)
				(type default)
			)
			(layer "F.Fab")
		)
		(fp_line
			(start -0.3048 0.9906)
			(end 0.3048 0.9906)
			(stroke
				(width 0.1)
				(type default)
			)
			(layer "F.Fab")
		)
		(fp_line
			(start -0.3048 -0.1016)
			(end -0.3048 0.9906)
			(stroke
				(width 0.1)
				(type default)
			)
			(layer "F.Fab")
		)
		(pad "1" smd rect
			(at 0 0 180)
			(size 0.508 0.508)
			(layers "F.Cu" "F.Mask" "F.Paste")
			(net "A_TSENSE_PVSA_CPU1")
		)
		(pad "2" smd rect
			(at 0 0.889 180)
			(size 0.508 0.508)
			(layers "F.Cu" "F.Mask" "F.Paste")
			(net "GND")
		)
		(zone
			(layer "F.Cu")
			(hatch none 0.5)
			(connect_pads
				(clearance 0)
			)
			(min_thickness 0.25)
			(keepout
				(tracks allowed)
				(vias not_allowed)
				(pads allowed)
				(copperpour not_allowed)
				(footprints allowed)
			)
			(placement
				(enabled no)
				(sheetname "")
			)
			(fill
				(thermal_gap 0.5)
				(thermal_bridge_width 0.5)
				(island_removal_mode 0)
			)
			(polygon
				(pts
					(xy 20.2692 -97.564956) (xy 20.7772 -97.564956) (xy 20.7772 -97.945956) (xy 20.2692 -97.945956)
				)
			)
		)
		(zone
			(layer "F.Cu")
			(hatch none 0.5)
			(connect_pads
				(clearance 0)
			)
			(min_thickness 0.25)
			(keepout
				(tracks not_allowed)
				(vias allowed)
				(pads allowed)
				(copperpour not_allowed)
				(footprints allowed)
			)
			(placement
				(enabled no)
				(sheetname "")
			)
			(fill
				(thermal_gap 0.5)
				(thermal_bridge_width 0.5)
				(island_removal_mode 0)
			)
			(polygon
				(pts
					(xy 20.2692 -97.564956) (xy 20.7772 -97.564956) (xy 20.7772 -97.945956) (xy 20.2692 -97.945956)
				)
			)
		)
	)
	(footprint ""
		(layer "F.Cu")
		(at 332.172818 -129.921)
		(property "Reference" "C6B3"
			(at 0 0 0)
			(layer "F.SilkS")
			(hide yes)
			(effects
				(font
					(size 1.27 1.27)
				)
			)
		)
		(property "Value" ""
			(at 0 0 0)
			(layer "F.Fab")
			(effects
				(font
					(size 1.27 1.27)
				)
			)
		)
		(duplicate_pad_numbers_are_jumpers no)
		(fp_poly
			(pts
				(xy -0.7239 -0.2159) (xy 0.7239 -0.2159) (xy 0.7239 1.9939) (xy -0.7239 1.9939)
			)
			(stroke
				(width 0)
				(type default)
			)
			(fill no)
			(layer "F.CrtYd")
		)
		(fp_line
			(start -0.7239 -0.2159)
			(end -0.7239 1.9939)
			(stroke
				(width 0.1)
				(type default)
			)
			(layer "F.Fab")
		)
		(fp_line
			(start -0.7239 1.9939)
			(end 0.7239 1.9939)
			(stroke
				(width 0.1)
				(type default)
			)
			(layer "F.Fab")
		)
		(fp_line
			(start 0.7239 -0.2159)
			(end -0.7239 -0.2159)
			(stroke
				(width 0.1)
				(type default)
			)
			(layer "F.Fab")
		)
		(fp_line
			(start 0.7239 1.9939)
			(end 0.7239 -0.2159)
			(stroke
				(width 0.1)
				(type default)
			)
			(layer "F.Fab")
		)
		(pad "1" smd rect
			(at 0 0)
			(size 1.27 1.016)
			(layers "F.Cu" "F.Mask" "F.Paste")
			(net "PVPP_DEF")
		)
		(pad "2" smd rect
			(at 0 1.778)
			(size 1.27 1.016)
			(layers "F.Cu" "F.Mask" "F.Paste")
			(net "GND")
		)
		(zone
			(layer "F.Cu")
			(hatch none 0.5)
			(connect_pads
				(clearance 0)
			)
			(min_thickness 0.25)
			(keepout
				(tracks not_allowed)
				(vias allowed)
				(pads allowed)
				(copperpour not_allowed)
				(footprints allowed)
			)
			(placement
				(enabled no)
				(sheetname "")
			)
			(fill
				(thermal_gap 0.5)
				(thermal_bridge_width 0.5)
				(island_removal_mode 0)
			)
			(polygon
				(pts
					(xy 331.537818 -129.413) (xy 332.807818 -129.413) (xy 332.807818 -128.651) (xy 331.537818 -128.651)
				)
			)
		)
	)
)
